(kicad_pcb
	(version 20260206)
	(generator "pcbnew")
	(generator_version "10.0")
	(general
		(thickness 1.6)
		(legacy_teardrops no)
	)
	(paper "A4")
	(title_block
		(title "01162023_DA0F0TEBIF0_F0T_Expander_BD_F_brd_V02_OCP.brd")
		(comment 1 "Grand Teton / footprints 5509-5514 of 9728")
	)
	(layers
		(0 "F.Cu" signal "TOP")
		(4 "In1.Cu" signal "GND")
		(6 "In2.Cu" signal "VCC")
		(8 "In3.Cu" signal "VCC1")
		(10 "In4.Cu" signal "GND1")
		(12 "In5.Cu" signal "IN1")
		(14 "In6.Cu" signal "GND2")
		(16 "In7.Cu" signal "IN2")
		(18 "In8.Cu" signal "GND3")
		(20 "In9.Cu" signal "IN3")
		(22 "In10.Cu" signal "GND4")
		(24 "In11.Cu" signal "IN4")
		(26 "In12.Cu" signal "GND5")
		(28 "In13.Cu" signal "IN5")
		(30 "In14.Cu" signal "GND6")
		(32 "In15.Cu" signal "IN6")
		(34 "In16.Cu" signal "GND7")
		(2 "B.Cu" signal "BOTTOM")
		(9 "F.Adhes" user "F.Adhesive")
		(11 "B.Adhes" user "B.Adhesive")
		(13 "F.Paste" user "Package Geometry/Pastemask Top")
		(15 "B.Paste" user "Package Geometry/Pastemask Bottom")
		(5 "F.SilkS" user "Ref Des/Silkscreen Top")
		(7 "B.SilkS" user "Ref Des/Silkscreen Bottom")
		(1 "F.Mask" user "Board Geometry/Soldermask Top")
		(3 "B.Mask" user "Board Geometry/Soldermask Bottom")
		(17 "Dwgs.User" user "User.Drawings")
		(19 "Cmts.User" user "User.Comments")
		(21 "Eco1.User" user "User.Eco1")
		(23 "Eco2.User" user "User.Eco2")
		(25 "Edge.Cuts" user "Board Geometry/Outline")
		(27 "Margin" user)
		(31 "F.CrtYd" user "Package Geometry/Place Bound Top")
		(29 "B.CrtYd" user "Package Geometry/Place Bound Bottom")
		(35 "F.Fab" user "Ref Des/Assembly Top")
		(33 "B.Fab" user "Ref Des/Assembly Bottom")
	)
	(footprint ""
		(layer "F.Cu")
		(at 437.798464 -297.46448)
		(property "Reference" "R4006"
			(at 0 0 0)
			(layer "F.SilkS")
			(hide yes)
			(effects
				(font
					(size 1.27 1.27)
				)
			)
		)
		(property "Value" ""
			(at 0 0 0)
			(layer "F.Fab")
			(effects
				(font
					(size 1.27 1.27)
				)
			)
		)
		(duplicate_pad_numbers_are_jumpers no)
		(fp_line
			(start -0.7874 -0.4064)
			(end 0.7874 -0.4064)
			(stroke
				(width 0.1524)
				(type default)
			)
			(layer "F.SilkS")
		)
		(fp_line
			(start -0.7874 0.4064)
			(end -0.7874 -0.4064)
			(stroke
				(width 0.1524)
				(type default)
			)
			(layer "F.SilkS")
		)
		(fp_line
			(start 0.7874 -0.4064)
			(end 0.7874 0.4064)
			(stroke
				(width 0.1524)
				(type default)
			)
			(layer "F.SilkS")
		)
		(fp_line
			(start 0.7874 0.4064)
			(end -0.7874 0.4064)
			(stroke
				(width 0.1524)
				(type default)
			)
			(layer "F.SilkS")
		)
		(fp_line
			(start -0.67945 -0.305054)
			(end -0.12065 -0.305054)
			(stroke
				(width 0.1)
				(type default)
			)
			(layer "F.Fab")
		)
		(fp_line
			(start -0.67945 0.3048)
			(end -0.67945 -0.305054)
			(stroke
				(width 0.1)
				(type default)
			)
			(layer "F.Fab")
		)
		(fp_line
			(start -0.12065 -0.305054)
			(end -0.12065 -0.2794)
			(stroke
				(width 0.1)
				(type default)
			)
			(layer "F.Fab")
		)
		(fp_line
			(start -0.12065 -0.2794)
			(end 0.12065 -0.2794)
			(stroke
				(width 0.1)
				(type default)
			)
			(layer "F.Fab")
		)
		(fp_line
			(start -0.12065 0.2794)
			(end -0.12065 0.3048)
			(stroke
				(width 0.1)
				(type default)
			)
			(layer "F.Fab")
		)
		(fp_line
			(start -0.12065 0.3048)
			(end -0.67945 0.3048)
			(stroke
				(width 0.1)
				(type default)
			)
			(layer "F.Fab")
		)
		(fp_line
			(start 0.120396 0.2794)
			(end -0.12065 0.2794)
			(stroke
				(width 0.1)
				(type default)
			)
			(layer "F.Fab")
		)
		(fp_line
			(start 0.120396 0.3048)
			(end 0.120396 0.2794)
			(stroke
				(width 0.1)
				(type default)
			)
			(layer "F.Fab")
		)
		(fp_line
			(start 0.12065 -0.3048)
			(end 0.67945 -0.3048)
			(stroke
				(width 0.1)
				(type default)
			)
			(layer "F.Fab")
		)
		(fp_line
			(start 0.12065 -0.2794)
			(end 0.12065 -0.3048)
			(stroke
				(width 0.1)
				(type default)
			)
			(layer "F.Fab")
		)
		(fp_line
			(start 0.67945 -0.3048)
			(end 0.67945 0.3048)
			(stroke
				(width 0.1)
				(type default)
			)
			(layer "F.Fab")
		)
		(fp_line
			(start 0.67945 0.3048)
			(end 0.120396 0.3048)
			(stroke
				(width 0.1)
				(type default)
			)
			(layer "F.Fab")
		)
		(pad "1" smd circle
			(at -0.40005 0)
			(size 0 0)
			(layers "F.Cu" "F.Mask" "F.Paste")
			(net "SMB_PEX3_HOST_LS_SDA")
		)
		(pad "2" smd circle
			(at 0.40005 0)
			(size 0 0)
			(layers "F.Cu" "F.Mask" "F.Paste")
			(net "I2C_PEX3_HOST_R_SDA")
		)
	)
	(footprint ""
		(layer "F.Cu")
		(at 361.188 -181.102 180)
		(property "Reference" "R4718"
			(at 0 0 180)
			(layer "F.SilkS")
			(hide yes)
			(effects
				(font
					(size 1.27 1.27)
				)
			)
		)
		(property "Value" ""
			(at 0 0 180)
			(layer "F.Fab")
			(effects
				(font
					(size 1.27 1.27)
				)
			)
		)
		(duplicate_pad_numbers_are_jumpers no)
		(fp_line
			(start 0.7874 0.4064)
			(end -0.7874 0.4064)
			(stroke
				(width 0.1524)
				(type default)
			)
			(layer "F.SilkS")
		)
		(fp_line
			(start 0.7874 -0.4064)
			(end 0.7874 0.4064)
			(stroke
				(width 0.1524)
				(type default)
			)
			(layer "F.SilkS")
		)
		(fp_line
			(start -0.7874 0.4064)
			(end -0.7874 -0.4064)
			(stroke
				(width 0.1524)
				(type default)
			)
			(layer "F.SilkS")
		)
		(fp_line
			(start -0.7874 -0.4064)
			(end 0.7874 -0.4064)
			(stroke
				(width 0.1524)
				(type default)
			)
			(layer "F.SilkS")
		)
		(fp_line
			(start 0.67945 0.3048)
			(end 0.120396 0.3048)
			(stroke
				(width 0.1)
				(type default)
			)
			(layer "F.Fab")
		)
		(fp_line
			(start 0.67945 -0.3048)
			(end 0.67945 0.3048)
			(stroke
				(width 0.1)
				(type default)
			)
			(layer "F.Fab")
		)
		(fp_line
			(start 0.12065 -0.2794)
			(end 0.12065 -0.3048)
			(stroke
				(width 0.1)
				(type default)
			)
			(layer "F.Fab")
		)
		(fp_line
			(start 0.12065 -0.3048)
			(end 0.67945 -0.3048)
			(stroke
				(width 0.1)
				(type default)
			)
			(layer "F.Fab")
		)
		(fp_line
			(start 0.120396 0.3048)
			(end 0.120396 0.2794)
			(stroke
				(width 0.1)
				(type default)
			)
			(layer "F.Fab")
		)
		(fp_line
			(start 0.120396 0.2794)
			(end -0.12065 0.2794)
			(stroke
				(width 0.1)
				(type default)
			)
			(layer "F.Fab")
		)
		(fp_line
			(start -0.12065 0.3048)
			(end -0.67945 0.3048)
			(stroke
				(width 0.1)
				(type default)
			)
			(layer "F.Fab")
		)
		(fp_line
			(start -0.12065 0.2794)
			(end -0.12065 0.3048)
			(stroke
				(width 0.1)
				(type default)
			)
			(layer "F.Fab")
		)
		(fp_line
			(start -0.12065 -0.2794)
			(end 0.12065 -0.2794)
			(stroke
				(width 0.1)
				(type default)
			)
			(layer "F.Fab")
		)
		(fp_line
			(start -0.12065 -0.305054)
			(end -0.12065 -0.2794)
			(stroke
				(width 0.1)
				(type default)
			)
			(layer "F.Fab")
		)
		(fp_line
			(start -0.67945 0.3048)
			(end -0.67945 -0.305054)
			(stroke
				(width 0.1)
				(type default)
			)
			(layer "F.Fab")
		)
		(fp_line
			(start -0.67945 -0.305054)
			(end -0.12065 -0.305054)
			(stroke
				(width 0.1)
				(type default)
			)
			(layer "F.Fab")
		)
		(pad "1" smd circle
			(at -0.40005 0 180)
			(size 0 0)
			(layers "F.Cu" "F.Mask" "F.Paste")
			(net "GND")
		)
		(pad "2" smd circle
			(at 0.40005 0 180)
			(size 0 0)
			(layers "F.Cu" "F.Mask" "F.Paste")
			(net "PCA9555_1_PEX1_A1")
		)
	)
	(footprint ""
		(layer "F.Cu")
		(at 114.582194 -37.025072)
		(property "Reference" "R5669"
			(at 0 0 0)
			(layer "F.SilkS")
			(hide yes)
			(effects
				(font
					(size 1.27 1.27)
				)
			)
		)
		(property "Value" ""
			(at 0 0 0)
			(layer "F.Fab")
			(effects
				(font
					(size 1.27 1.27)
				)
			)
		)
		(duplicate_pad_numbers_are_jumpers no)
		(fp_line
			(start -0.7874 -0.4064)
			(end 0.7874 -0.4064)
			(stroke
				(width 0.1524)
				(type default)
			)
			(layer "F.SilkS")
		)
		(fp_line
			(start -0.7874 0.4064)
			(end -0.7874 -0.4064)
			(stroke
				(width 0.1524)
				(type default)
			)
			(layer "F.SilkS")
		)
		(fp_line
			(start 0.7874 -0.4064)
			(end 0.7874 0.4064)
			(stroke
				(width 0.1524)
				(type default)
			)
			(layer "F.SilkS")
		)
		(fp_line
			(start 0.7874 0.4064)
			(end -0.7874 0.4064)
			(stroke
				(width 0.1524)
				(type default)
			)
			(layer "F.SilkS")
		)
		(fp_line
			(start -0.67945 -0.305054)
			(end -0.12065 -0.305054)
			(stroke
				(width 0.1)
				(type default)
			)
			(layer "F.Fab")
		)
		(fp_line
			(start -0.67945 0.3048)
			(end -0.67945 -0.305054)
			(stroke
				(width 0.1)
				(type default)
			)
			(layer "F.Fab")
		)
		(fp_line
			(start -0.12065 -0.305054)
			(end -0.12065 -0.2794)
			(stroke
				(width 0.1)
				(type default)
			)
			(layer "F.Fab")
		)
		(fp_line
			(start -0.12065 -0.2794)
			(end 0.12065 -0.2794)
			(stroke
				(width 0.1)
				(type default)
			)
			(layer "F.Fab")
		)
		(fp_line
			(start -0.12065 0.2794)
			(end -0.12065 0.3048)
			(stroke
				(width 0.1)
				(type default)
			)
			(layer "F.Fab")
		)
		(fp_line
			(start -0.12065 0.3048)
			(end -0.67945 0.3048)
			(stroke
				(width 0.1)
				(type default)
			)
			(layer "F.Fab")
		)
		(fp_line
			(start 0.120396 0.2794)
			(end -0.12065 0.2794)
			(stroke
				(width 0.1)
				(type default)
			)
			(layer "F.Fab")
		)
		(fp_line
			(start 0.120396 0.3048)
			(end 0.120396 0.2794)
			(stroke
				(width 0.1)
				(type default)
			)
			(layer "F.Fab")
		)
		(fp_line
			(start 0.12065 -0.3048)
			(end 0.67945 -0.3048)
			(stroke
				(width 0.1)
				(type default)
			)
			(layer "F.Fab")
		)
		(fp_line
			(start 0.12065 -0.2794)
			(end 0.12065 -0.3048)
			(stroke
				(width 0.1)
				(type default)
			)
			(layer "F.Fab")
		)
		(fp_line
			(start 0.67945 -0.3048)
			(end 0.67945 0.3048)
			(stroke
				(width 0.1)
				(type default)
			)
			(layer "F.Fab")
		)
		(fp_line
			(start 0.67945 0.3048)
			(end 0.120396 0.3048)
			(stroke
				(width 0.1)
				(type default)
			)
			(layer "F.Fab")
		)
		(pad "1" smd circle
			(at -0.40005 0)
			(size 0 0)
			(layers "F.Cu" "F.Mask" "F.Paste")
			(net "RST_SMB_SSD_R_N")
		)
		(pad "2" smd circle
			(at 0.40005 0)
			(size 0 0)
			(layers "F.Cu" "F.Mask" "F.Paste")
			(net "RST_SMB_SSD4_N")
		)
	)
	(footprint ""
		(layer "F.Cu")
		(at 138.985244 -91.242642 180)
		(property "Reference" "R1565"
			(at 0 0 180)
			(layer "F.SilkS")
			(hide yes)
			(effects
				(font
					(size 1.27 1.27)
				)
			)
		)
		(property "Value" ""
			(at 0 0 180)
			(layer "F.Fab")
			(effects
				(font
					(size 1.27 1.27)
				)
			)
		)
		(duplicate_pad_numbers_are_jumpers no)
		(fp_line
			(start 0.7874 0.4064)
			(end -0.7874 0.4064)
			(stroke
				(width 0.1524)
				(type default)
			)
			(layer "F.SilkS")
		)
		(fp_line
			(start 0.7874 -0.4064)
			(end 0.7874 0.4064)
			(stroke
				(width 0.1524)
				(type default)
			)
			(layer "F.SilkS")
		)
		(fp_line
			(start -0.7874 0.4064)
			(end -0.7874 -0.4064)
			(stroke
				(width 0.1524)
				(type default)
			)
			(layer "F.SilkS")
		)
		(fp_line
			(start -0.7874 -0.4064)
			(end 0.7874 -0.4064)
			(stroke
				(width 0.1524)
				(type default)
			)
			(layer "F.SilkS")
		)
		(fp_line
			(start 0.67945 0.3048)
			(end 0.120396 0.3048)
			(stroke
				(width 0.1)
				(type default)
			)
			(layer "F.Fab")
		)
		(fp_line
			(start 0.67945 -0.3048)
			(end 0.67945 0.3048)
			(stroke
				(width 0.1)
				(type default)
			)
			(layer "F.Fab")
		)
		(fp_line
			(start 0.12065 -0.2794)
			(end 0.12065 -0.3048)
			(stroke
				(width 0.1)
				(type default)
			)
			(layer "F.Fab")
		)
		(fp_line
			(start 0.12065 -0.3048)
			(end 0.67945 -0.3048)
			(stroke
				(width 0.1)
				(type default)
			)
			(layer "F.Fab")
		)
		(fp_line
			(start 0.120396 0.3048)
			(end 0.120396 0.2794)
			(stroke
				(width 0.1)
				(type default)
			)
			(layer "F.Fab")
		)
		(fp_line
			(start 0.120396 0.2794)
			(end -0.12065 0.2794)
			(stroke
				(width 0.1)
				(type default)
			)
			(layer "F.Fab")
		)
		(fp_line
			(start -0.12065 0.3048)
			(end -0.67945 0.3048)
			(stroke
				(width 0.1)
				(type default)
			)
			(layer "F.Fab")
		)
		(fp_line
			(start -0.12065 0.2794)
			(end -0.12065 0.3048)
			(stroke
				(width 0.1)
				(type default)
			)
			(layer "F.Fab")
		)
		(fp_line
			(start -0.12065 -0.2794)
			(end 0.12065 -0.2794)
			(stroke
				(width 0.1)
				(type default)
			)
			(layer "F.Fab")
		)
		(fp_line
			(start -0.12065 -0.305054)
			(end -0.12065 -0.2794)
			(stroke
				(width 0.1)
				(type default)
			)
			(layer "F.Fab")
		)
		(fp_line
			(start -0.67945 0.3048)
			(end -0.67945 -0.305054)
			(stroke
				(width 0.1)
				(type default)
			)
			(layer "F.Fab")
		)
		(fp_line
			(start -0.67945 -0.305054)
			(end -0.12065 -0.305054)
			(stroke
				(width 0.1)
				(type default)
			)
			(layer "F.Fab")
		)
		(pad "1" smd circle
			(at -0.40005 0 180)
			(size 0 0)
			(layers "F.Cu" "F.Mask" "F.Paste")
			(net "P3V3_AUX")
		)
		(pad "2" smd circle
			(at 0.40005 0 180)
			(size 0 0)
			(layers "F.Cu" "F.Mask" "F.Paste")
			(net "SMB_BIC_I2C9_MUX0_SSD5_R_SCL")
		)
	)
	(footprint ""
		(layer "F.Cu")
		(at 129.310384 -192.35166 -90)
		(property "Reference" "R6676"
			(at 0 0 270)
			(layer "F.SilkS")
			(hide yes)
			(effects
				(font
					(size 1.27 1.27)
				)
			)
		)
		(property "Value" ""
			(at 0 0 270)
			(layer "F.Fab")
			(effects
				(font
					(size 1.27 1.27)
				)
			)
		)
		(duplicate_pad_numbers_are_jumpers no)
		(fp_line
			(start -0.7874 0.4064)
			(end -0.7874 -0.4064)
			(stroke
				(width 0.1524)
				(type default)
			)
			(layer "F.SilkS")
		)
		(fp_line
			(start 0.7874 0.4064)
			(end -0.7874 0.4064)
			(stroke
				(width 0.1524)
				(type default)
			)
			(layer "F.SilkS")
		)
		(fp_line
			(start -0.7874 -0.4064)
			(end 0.7874 -0.4064)
			(stroke
				(width 0.1524)
				(type default)
			)
			(layer "F.SilkS")
		)
		(fp_line
			(start 0.7874 -0.4064)
			(end 0.7874 0.4064)
			(stroke
				(width 0.1524)
				(type default)
			)
			(layer "F.SilkS")
		)
		(fp_line
			(start -0.67945 0.3048)
			(end -0.67945 -0.305054)
			(stroke
				(width 0.1)
				(type default)
			)
			(layer "F.Fab")
		)
		(fp_line
			(start -0.12065 0.3048)
			(end -0.67945 0.3048)
			(stroke
				(width 0.1)
				(type default)
			)
			(layer "F.Fab")
		)
		(fp_line
			(start 0.120396 0.3048)
			(end 0.120396 0.2794)
			(stroke
				(width 0.1)
				(type default)
			)
			(layer "F.Fab")
		)
		(fp_line
			(start 0.67945 0.3048)
			(end 0.120396 0.3048)
			(stroke
				(width 0.1)
				(type default)
			)
			(layer "F.Fab")
		)
		(fp_line
			(start -0.12065 0.2794)
			(end -0.12065 0.3048)
			(stroke
				(width 0.1)
				(type default)
			)
			(layer "F.Fab")
		)
		(fp_line
			(start 0.120396 0.2794)
			(end -0.12065 0.2794)
			(stroke
				(width 0.1)
				(type default)
			)
			(layer "F.Fab")
		)
		(fp_line
			(start -0.12065 -0.2794)
			(end 0.12065 -0.2794)
			(stroke
				(width 0.1)
				(type default)
			)
			(layer "F.Fab")
		)
		(fp_line
			(start 0.12065 -0.2794)
			(end 0.12065 -0.3048)
			(stroke
				(width 0.1)
				(type default)
			)
			(layer "F.Fab")
		)
		(fp_line
			(start 0.12065 -0.3048)
			(end 0.67945 -0.3048)
			(stroke
				(width 0.1)
				(type default)
			)
			(layer "F.Fab")
		)
		(fp_line
			(start 0.67945 -0.3048)
			(end 0.67945 0.3048)
			(stroke
				(width 0.1)
				(type default)
			)
			(layer "F.Fab")
		)
		(fp_line
			(start -0.67945 -0.305054)
			(end -0.12065 -0.305054)
			(stroke
				(width 0.1)
				(type default)
			)
			(layer "F.Fab")
		)
		(fp_line
			(start -0.12065 -0.305054)
			(end -0.12065 -0.2794)
			(stroke
				(width 0.1)
				(type default)
			)
			(layer "F.Fab")
		)
		(pad "1" smd circle
			(at -0.40005 0 270)
			(size 0 0)
			(layers "F.Cu" "F.Mask" "F.Paste")
			(net "NIC7_CLK_EN_BUF_R_N")
		)
		(pad "2" smd circle
			(at 0.40005 0 270)
			(size 0 0)
			(layers "F.Cu" "F.Mask" "F.Paste")
			(net "P3V3")
		)
	)
	(footprint ""
		(layer "F.Cu")
		(at 359.156 -193.294)
		(property "Reference" "R4618"
			(at 0 0 0)
			(layer "F.SilkS")
			(hide yes)
			(effects
				(font
					(size 1.27 1.27)
				)
			)
		)
		(property "Value" ""
			(at 0 0 0)
			(layer "F.Fab")
			(effects
				(font
					(size 1.27 1.27)
				)
			)
		)
		(duplicate_pad_numbers_are_jumpers no)
		(fp_line
			(start -0.7874 -0.4064)
			(end 0.7874 -0.4064)
			(stroke
				(width 0.1524)
				(type default)
			)
			(layer "F.SilkS")
		)
		(fp_line
			(start -0.7874 0.4064)
			(end -0.7874 -0.4064)
			(stroke
				(width 0.1524)
				(type default)
			)
			(layer "F.SilkS")
		)
		(fp_line
			(start 0.7874 -0.4064)
			(end 0.7874 0.4064)
			(stroke
				(width 0.1524)
				(type default)
			)
			(layer "F.SilkS")
		)
		(fp_line
			(start 0.7874 0.4064)
			(end -0.7874 0.4064)
			(stroke
				(width 0.1524)
				(type default)
			)
			(layer "F.SilkS")
		)
		(fp_line
			(start -0.67945 -0.305054)
			(end -0.12065 -0.305054)
			(stroke
				(width 0.1)
				(type default)
			)
			(layer "F.Fab")
		)
		(fp_line
			(start -0.67945 0.3048)
			(end -0.67945 -0.305054)
			(stroke
				(width 0.1)
				(type default)
			)
			(layer "F.Fab")
		)
		(fp_line
			(start -0.12065 -0.305054)
			(end -0.12065 -0.2794)
			(stroke
				(width 0.1)
				(type default)
			)
			(layer "F.Fab")
		)
		(fp_line
			(start -0.12065 -0.2794)
			(end 0.12065 -0.2794)
			(stroke
				(width 0.1)
				(type default)
			)
			(layer "F.Fab")
		)
		(fp_line
			(start -0.12065 0.2794)
			(end -0.12065 0.3048)
			(stroke
				(width 0.1)
				(type default)
			)
			(layer "F.Fab")
		)
		(fp_line
			(start -0.12065 0.3048)
			(end -0.67945 0.3048)
			(stroke
				(width 0.1)
				(type default)
			)
			(layer "F.Fab")
		)
		(fp_line
			(start 0.120396 0.2794)
			(end -0.12065 0.2794)
			(stroke
				(width 0.1)
				(type default)
			)
			(layer "F.Fab")
		)
		(fp_line
			(start 0.120396 0.3048)
			(end 0.120396 0.2794)
			(stroke
				(width 0.1)
				(type default)
			)
			(layer "F.Fab")
		)
		(fp_line
			(start 0.12065 -0.3048)
			(end 0.67945 -0.3048)
			(stroke
				(width 0.1)
				(type default)
			)
			(layer "F.Fab")
		)
		(fp_line
			(start 0.12065 -0.2794)
			(end 0.12065 -0.3048)
			(stroke
				(width 0.1)
				(type default)
			)
			(layer "F.Fab")
		)
		(fp_line
			(start 0.67945 -0.3048)
			(end 0.67945 0.3048)
			(stroke
				(width 0.1)
				(type default)
			)
			(layer "F.Fab")
		)
		(fp_line
			(start 0.67945 0.3048)
			(end 0.120396 0.3048)
			(stroke
				(width 0.1)
				(type default)
			)
			(layer "F.Fab")
		)
		(pad "1" smd circle
			(at -0.40005 0)
			(size 0 0)
			(layers "F.Cu" "F.Mask" "F.Paste")
			(net "PEX0_PCA9555_INT_N")
		)
		(pad "2" smd circle
			(at 0.40005 0)
			(size 0 0)
			(layers "F.Cu" "F.Mask" "F.Paste")
			(net "PEX0_PCA9555_1_INT_N")
		)
	)
)
